# T6G (Grand Teton) — schematic netlist excerpt (pin names and nets, part order shuffled) for the footprints in the layout excerpt that follows; sources: Cadence DE-HDL packaged netlist, KiCad conversion of 04192023_DAF0TMB3IC0_F0TG_MB_C_brd_V02_OCP.brd

C2314  Q_CAP  22UF 4V 20% X6S  pkg C0402  page 73 : A = PVDDCR_CPU0_P1 ; B = GND
C1092  Q_CAP  0.1UF 25V 10% X7R  pkg 0402  page 258 : A = P1V8_AUX_ADC_TIC ; B = GND

(kicad_pcb
	(version 20260206)
	(generator "pcbnew")
	(generator_version "10.0")
	(general
		(thickness 1.6)
		(legacy_teardrops no)
	)
	(paper "A4")
	(title_block
		(title "04192023_DAF0TMB3IC0_F0TG_MB_C_brd_V02_OCP.brd")
		(comment 1 "Grand Teton / footprints 5886-5887 of 8354")
	)
	(layers
		(0 "F.Cu" signal "TOP")
		(4 "In1.Cu" signal "GND")
		(6 "In2.Cu" signal "IN1")
		(8 "In3.Cu" signal "GND1")
		(10 "In4.Cu" signal "IN2")
		(12 "In5.Cu" signal "GND2")
		(14 "In6.Cu" signal "IN3")
		(16 "In7.Cu" signal "GND3")
		(18 "In8.Cu" signal "VCC")
		(20 "In9.Cu" signal "VCC1")
		(22 "In10.Cu" signal "GND4")
		(24 "In11.Cu" signal "IN4")
		(26 "In12.Cu" signal "GND5")
		(28 "In13.Cu" signal "IN5")
		(30 "In14.Cu" signal "GND6")
		(32 "In15.Cu" signal "IN6")
		(34 "In16.Cu" signal "GND7")
		(2 "B.Cu" signal "BOTTOM")
		(9 "F.Adhes" user "F.Adhesive")
		(11 "B.Adhes" user "B.Adhesive")
		(13 "F.Paste" user "Package Geometry/Pastemask Top")
		(15 "B.Paste" user "Package Geometry/Pastemask Bottom")
		(5 "F.SilkS" user "Ref Des/Silkscreen Top")
		(7 "B.SilkS" user "Ref Des/Silkscreen Bottom")
		(1 "F.Mask" user "Board Geometry/Soldermask Top")
		(3 "B.Mask" user "Board Geometry/Soldermask Bottom")
		(17 "Dwgs.User" user "User.Drawings")
		(19 "Cmts.User" user "User.Comments")
		(21 "Eco1.User" user "User.Eco1")
		(23 "Eco2.User" user "User.Eco2")
		(25 "Edge.Cuts" user "Board Geometry/Outline")
		(27 "Margin" user)
		(31 "F.CrtYd" user "Package Geometry/Place Bound Top")
		(29 "B.CrtYd" user "Package Geometry/Place Bound Bottom")
		(35 "F.Fab" user "Ref Des/Assembly Top")
		(33 "B.Fab" user "Ref Des/Assembly Bottom")
	)
	(footprint ""
		(layer "B.Cu")
		(at 107.101386 -248.479564 180)
		(property "Reference" "C2314"
			(at 0 0 0)
			(layer "B.SilkS")
			(hide yes)
			(effects
				(font
					(size 1.27 1.27)
				)
				(justify mirror)
			)
		)
		(property "Value" ""
			(at 0 0 0)
			(layer "B.Fab")
			(effects
				(font
					(size 1.27 1.27)
				)
				(justify mirror)
			)
		)
		(duplicate_pad_numbers_are_jumpers no)
		(fp_line
			(start 0.7874 0.4064)
			(end 0.7874 -0.4064)
			(stroke
				(width 0.1524)
				(type default)
			)
			(layer "B.SilkS")
		)
		(fp_line
			(start 0.7874 -0.4064)
			(end -0.7874 -0.4064)
			(stroke
				(width 0.1524)
				(type default)
			)
			(layer "B.SilkS")
		)
		(fp_line
			(start -0.7874 0.4064)
			(end 0.7874 0.4064)
			(stroke
				(width 0.1524)
				(type default)
			)
			(layer "B.SilkS")
		)
		(fp_line
			(start -0.7874 -0.4064)
			(end -0.7874 0.4064)
			(stroke
				(width 0.1524)
				(type default)
			)
			(layer "B.SilkS")
		)
		(fp_line
			(start 0.67945 0.3048)
			(end 0.67945 -0.305054)
			(stroke
				(width 0.1)
				(type default)
			)
			(layer "B.Fab")
		)
		(fp_line
			(start 0.67945 -0.305054)
			(end 0.12065 -0.305054)
			(stroke
				(width 0.1)
				(type default)
			)
			(layer "B.Fab")
		)
		(fp_line
			(start 0.12065 0.3048)
			(end 0.67945 0.3048)
			(stroke
				(width 0.1)
				(type default)
			)
			(layer "B.Fab")
		)
		(fp_line
			(start 0.12065 0.2794)
			(end 0.12065 0.3048)
			(stroke
				(width 0.1)
				(type default)
			)
			(layer "B.Fab")
		)
		(fp_line
			(start 0.12065 -0.2794)
			(end -0.12065 -0.2794)
			(stroke
				(width 0.1)
				(type default)
			)
			(layer "B.Fab")
		)
		(fp_line
			(start 0.12065 -0.305054)
			(end 0.12065 -0.2794)
			(stroke
				(width 0.1)
				(type default)
			)
			(layer "B.Fab")
		)
		(fp_line
			(start -0.120396 0.3048)
			(end -0.120396 0.2794)
			(stroke
				(width 0.1)
				(type default)
			)
			(layer "B.Fab")
		)
		(fp_line
			(start -0.120396 0.2794)
			(end 0.12065 0.2794)
			(stroke
				(width 0.1)
				(type default)
			)
			(layer "B.Fab")
		)
		(fp_line
			(start -0.12065 -0.2794)
			(end -0.12065 -0.3048)
			(stroke
				(width 0.1)
				(type default)
			)
			(layer "B.Fab")
		)
		(fp_line
			(start -0.12065 -0.3048)
			(end -0.67945 -0.3048)
			(stroke
				(width 0.1)
				(type default)
			)
			(layer "B.Fab")
		)
		(fp_line
			(start -0.67945 0.3048)
			(end -0.120396 0.3048)
			(stroke
				(width 0.1)
				(type default)
			)
			(layer "B.Fab")
		)
		(fp_line
			(start -0.67945 -0.3048)
			(end -0.67945 0.3048)
			(stroke
				(width 0.1)
				(type default)
			)
			(layer "B.Fab")
		)
		(pad "1" smd circle
			(at 0.40005 0)
			(size 0 0)
			(layers "B.Cu" "B.Mask" "B.Paste")
			(net "PVDDCR_CPU0_P1")
		)
		(pad "2" smd circle
			(at -0.40005 0)
			(size 0 0)
			(layers "B.Cu" "B.Mask" "B.Paste")
			(net "GND")
		)
	)
	(footprint ""
		(layer "B.Cu")
		(at 228.505258 -323.263768 180)
		(property "Reference" "C1092"
			(at 0 0 0)
			(layer "B.SilkS")
			(hide yes)
			(effects
				(font
					(size 1.27 1.27)
				)
				(justify mirror)
			)
		)
		(property "Value" ""
			(at 0 0 0)
			(layer "B.Fab")
			(effects
				(font
					(size 1.27 1.27)
				)
				(justify mirror)
			)
		)
		(duplicate_pad_numbers_are_jumpers no)
		(fp_line
			(start 0.7874 0.4064)
			(end 0.7874 -0.4064)
			(stroke
				(width 0.1524)
				(type default)
			)
			(layer "B.SilkS")
		)
		(fp_line
			(start 0.7874 -0.4064)
			(end -0.7874 -0.4064)
			(stroke
				(width 0.1524)
				(type default)
			)
			(layer "B.SilkS")
		)
		(fp_line
			(start -0.7874 0.4064)
			(end 0.7874 0.4064)
			(stroke
				(width 0.1524)
				(type default)
			)
			(layer "B.SilkS")
		)
		(fp_line
			(start -0.7874 -0.4064)
			(end -0.7874 0.4064)
			(stroke
				(width 0.1524)
				(type default)
			)
			(layer "B.SilkS")
		)
		(fp_line
			(start 0.67945 0.3048)
			(end 0.67945 -0.305054)
			(stroke
				(width 0.1)
				(type default)
			)
			(layer "B.Fab")
		)
		(fp_line
			(start 0.67945 -0.305054)
			(end 0.12065 -0.305054)
			(stroke
				(width 0.1)
				(type default)
			)
			(layer "B.Fab")
		)
		(fp_line
			(start 0.12065 0.3048)
			(end 0.67945 0.3048)
			(stroke
				(width 0.1)
				(type default)
			)
			(layer "B.Fab")
		)
		(fp_line
			(start 0.12065 0.2794)
			(end 0.12065 0.3048)
			(stroke
				(width 0.1)
				(type default)
			)
			(layer "B.Fab")
		)
		(fp_line
			(start 0.12065 -0.2794)
			(end -0.12065 -0.2794)
			(stroke
				(width 0.1)
				(type default)
			)
			(layer "B.Fab")
		)
		(fp_line
			(start 0.12065 -0.305054)
			(end 0.12065 -0.2794)
			(stroke
				(width 0.1)
				(type default)
			)
			(layer "B.Fab")
		)
		(fp_line
			(start -0.120396 0.3048)
			(end -0.120396 0.2794)
			(stroke
				(width 0.1)
				(type default)
			)
			(layer "B.Fab")
		)
		(fp_line
			(start -0.120396 0.2794)
			(end 0.12065 0.2794)
			(stroke
				(width 0.1)
				(type default)
			)
			(layer "B.Fab")
		)
		(fp_line
			(start -0.12065 -0.2794)
			(end -0.12065 -0.3048)
			(stroke
				(width 0.1)
				(type default)
			)
			(layer "B.Fab")
		)
		(fp_line
			(start -0.12065 -0.3048)
			(end -0.67945 -0.3048)
			(stroke
				(width 0.1)
				(type default)
			)
			(layer "B.Fab")
		)
		(fp_line
			(start -0.67945 0.3048)
			(end -0.120396 0.3048)
			(stroke
				(width 0.1)
				(type default)
			)
			(layer "B.Fab")
		)
		(fp_line
			(start -0.67945 -0.3048)
			(end -0.67945 0.3048)
			(stroke
				(width 0.1)
				(type default)
			)
			(layer "B.Fab")
		)
		(pad "1" smd circle
			(at 0.40005 0)
			(size 0 0)
			(layers "B.Cu" "B.Mask" "B.Paste")
			(net "P1V8_AUX_ADC_TIC")
		)
		(pad "2" smd circle
			(at -0.40005 0)
			(size 0 0)
			(layers "B.Cu" "B.Mask" "B.Paste")
			(net "GND")
		)
	)
)
